(kicad_pcb
	(version 20260206)
	(generator "pcbnew")
	(generator_version "10.0")
	(general
		(thickness 1.6)
		(legacy_teardrops no)
	)
	(paper "A4")
	(title_block
		(title "Wiwynn_Tioga_Pass_MB.brd")
		(comment 1 "Tioga Pass / footprint 4084 of 4770 (J9T1), pads 1-123 of 291")
	)
	(layers
		(0 "F.Cu" signal "TOP")
		(4 "In1.Cu" signal "L2GND")
		(6 "In2.Cu" signal "L3")
		(8 "In3.Cu" signal "L4GND")
		(10 "In4.Cu" signal "L5")
		(12 "In5.Cu" signal "L6GND")
		(14 "In6.Cu" signal "L7VCC")
		(16 "In7.Cu" signal "L8VCC")
		(18 "In8.Cu" signal "L9GND")
		(20 "In9.Cu" signal "L10")
		(22 "In10.Cu" signal "L11GND")
		(24 "In11.Cu" signal "L12")
		(26 "In12.Cu" signal "L13GND")
		(2 "B.Cu" signal "BOTTOM")
		(9 "F.Adhes" user "F.Adhesive")
		(11 "B.Adhes" user "B.Adhesive")
		(13 "F.Paste" user "Package Geometry/Pastemask Top")
		(15 "B.Paste" user "Package Geometry/Pastemask Bottom")
		(5 "F.SilkS" user "Ref Des/Silkscreen Top")
		(7 "B.SilkS" user "Ref Des/Silkscreen Bottom")
		(1 "F.Mask" user "Board Geometry/Soldermask Top")
		(3 "B.Mask" user "Board Geometry/Soldermask Bottom")
		(17 "Dwgs.User" user "User.Drawings")
		(19 "Cmts.User" user "User.Comments")
		(21 "Eco1.User" user "User.Eco1")
		(23 "Eco2.User" user "User.Eco2")
		(25 "Edge.Cuts" user "Board Geometry/Outline")
		(27 "Margin" user)
		(31 "F.CrtYd" user "Package Geometry/Place Bound Top")
		(29 "B.CrtYd" user "Package Geometry/Place Bound Bottom")
		(35 "F.Fab" user "Ref Des/Assembly Top")
		(33 "B.Fab" user "Ref Des/Assembly Bottom")
	)
	(footprint ""
		(layer "B.Cu")
		(at 29.699458 -24.824182 90)
		(property "Reference" "J9T1"
			(at 2.200148 39.261542 0)
			(unlocked yes)
			(layer "B.SilkS")
			(effects
				(font
					(size 0.7874 0.5842)
					(thickness 0.1524)
				)
				(justify left mirror)
			)
		)
		(property "Value" ""
			(at 0 0 90)
			(layer "B.Fab")
			(effects
				(font
					(size 1.27 1.27)
				)
				(justify mirror)
			)
		)
		(duplicate_pad_numbers_are_jumpers no)
		(pad "" thru_hole circle
			(at -2.29997 -5.649976 270)
			(size 2.8194 2.8194)
			(drill 2.4384)
			(layers "*.Cu" "*.Mask")
			(remove_unused_layers no)
			(clearance 0.127)
			(thermal_gap 0.127)
		)
		(pad "" thru_hole oval
			(at -2.29997 68.90004 270)
			(size 2.8194 1.5748)
			(drill oval 2.4384 1.1938)
			(layers "*.Cu" "*.Mask")
			(remove_unused_layers no)
			(clearance 0.127)
			(thermal_gap 0.127)
		)
		(pad "" thru_hole circle
			(at -2.29997 132.299964 270)
			(size 2.8194 2.8194)
			(drill 2.4384)
			(layers "*.Cu" "*.Mask")
			(remove_unused_layers no)
			(clearance 0.127)
			(thermal_gap 0.127)
		)
		(pad "1" smd rect
			(at 0 0 270)
			(size 1.8034 0.508)
			(layers "B.Cu" "B.Mask" "B.Paste")
			(net "P12V_NVDIMM_GHJ")
		)
		(pad "2" smd rect
			(at 0 0.849884 270)
			(size 1.8034 0.508)
			(layers "B.Cu" "B.Mask" "B.Paste")
			(net "GND")
		)
		(pad "3" smd rect
			(at 0 1.700022 270)
			(size 1.8034 0.508)
			(layers "B.Cu" "B.Mask" "B.Paste")
			(net "M_G_DQ<4>")
		)
		(pad "4" smd rect
			(at 0 2.549906 270)
			(size 1.8034 0.508)
			(layers "B.Cu" "B.Mask" "B.Paste")
			(net "GND")
		)
		(pad "5" smd rect
			(at 0 3.400044 270)
			(size 1.8034 0.508)
			(layers "B.Cu" "B.Mask" "B.Paste")
			(net "M_G_DQ<0>")
		)
		(pad "6" smd rect
			(at 0 4.249928 270)
			(size 1.8034 0.508)
			(layers "B.Cu" "B.Mask" "B.Paste")
			(net "GND")
		)
		(pad "7" smd rect
			(at 0 5.100066 270)
			(size 1.8034 0.508)
			(layers "B.Cu" "B.Mask" "B.Paste")
			(net "M_G_DQS_DP<9>")
		)
		(pad "8" smd rect
			(at 0 5.94995 270)
			(size 1.8034 0.508)
			(layers "B.Cu" "B.Mask" "B.Paste")
			(net "M_G_DQS_DN<9>")
		)
		(pad "9" smd rect
			(at 0 6.800088 270)
			(size 1.8034 0.508)
			(layers "B.Cu" "B.Mask" "B.Paste")
			(net "GND")
		)
		(pad "10" smd rect
			(at 0 7.649972 270)
			(size 1.8034 0.508)
			(layers "B.Cu" "B.Mask" "B.Paste")
			(net "M_G_DQ<6>")
		)
		(pad "11" smd rect
			(at 0 8.50011 270)
			(size 1.8034 0.508)
			(layers "B.Cu" "B.Mask" "B.Paste")
			(net "GND")
		)
		(pad "12" smd rect
			(at 0 9.349994 270)
			(size 1.8034 0.508)
			(layers "B.Cu" "B.Mask" "B.Paste")
			(net "M_G_DQ<2>")
		)
		(pad "13" smd rect
			(at 0 10.199878 270)
			(size 1.8034 0.508)
			(layers "B.Cu" "B.Mask" "B.Paste")
			(net "GND")
		)
		(pad "14" smd rect
			(at 0 11.050016 270)
			(size 1.8034 0.508)
			(layers "B.Cu" "B.Mask" "B.Paste")
			(net "M_G_DQ<12>")
		)
		(pad "15" smd rect
			(at 0 11.8999 270)
			(size 1.8034 0.508)
			(layers "B.Cu" "B.Mask" "B.Paste")
			(net "GND")
		)
		(pad "16" smd rect
			(at 0 12.750038 270)
			(size 1.8034 0.508)
			(layers "B.Cu" "B.Mask" "B.Paste")
			(net "M_G_DQ<8>")
		)
		(pad "17" smd rect
			(at 0 13.599922 270)
			(size 1.8034 0.508)
			(layers "B.Cu" "B.Mask" "B.Paste")
			(net "GND")
		)
		(pad "18" smd rect
			(at 0 14.45006 270)
			(size 1.8034 0.508)
			(layers "B.Cu" "B.Mask" "B.Paste")
			(net "M_G_DQS_DP<10>")
		)
		(pad "19" smd rect
			(at 0 15.299944 270)
			(size 1.8034 0.508)
			(layers "B.Cu" "B.Mask" "B.Paste")
			(net "M_G_DQS_DN<10>")
		)
		(pad "20" smd rect
			(at 0 16.150082 270)
			(size 1.8034 0.508)
			(layers "B.Cu" "B.Mask" "B.Paste")
			(net "GND")
		)
		(pad "21" smd rect
			(at 0 16.999966 270)
			(size 1.8034 0.508)
			(layers "B.Cu" "B.Mask" "B.Paste")
			(net "M_G_DQ<14>")
		)
		(pad "22" smd rect
			(at 0 17.850104 270)
			(size 1.8034 0.508)
			(layers "B.Cu" "B.Mask" "B.Paste")
			(net "GND")
		)
		(pad "23" smd rect
			(at 0 18.699988 270)
			(size 1.8034 0.508)
			(layers "B.Cu" "B.Mask" "B.Paste")
			(net "M_G_DQ<10>")
		)
		(pad "24" smd rect
			(at 0 19.550126 270)
			(size 1.8034 0.508)
			(layers "B.Cu" "B.Mask" "B.Paste")
			(net "GND")
		)
		(pad "25" smd rect
			(at 0 20.40001 270)
			(size 1.8034 0.508)
			(layers "B.Cu" "B.Mask" "B.Paste")
			(net "M_G_DQ<20>")
		)
		(pad "26" smd rect
			(at 0 21.249894 270)
			(size 1.8034 0.508)
			(layers "B.Cu" "B.Mask" "B.Paste")
			(net "GND")
		)
		(pad "27" smd rect
			(at 0 22.100032 270)
			(size 1.8034 0.508)
			(layers "B.Cu" "B.Mask" "B.Paste")
			(net "M_G_DQ<16>")
		)
		(pad "28" smd rect
			(at 0 22.949916 270)
			(size 1.8034 0.508)
			(layers "B.Cu" "B.Mask" "B.Paste")
			(net "GND")
		)
		(pad "29" smd rect
			(at 0 23.800054 270)
			(size 1.8034 0.508)
			(layers "B.Cu" "B.Mask" "B.Paste")
			(net "M_G_DQS_DP<11>")
		)
		(pad "30" smd rect
			(at 0 24.649938 270)
			(size 1.8034 0.508)
			(layers "B.Cu" "B.Mask" "B.Paste")
			(net "M_G_DQS_DN<11>")
		)
		(pad "31" smd rect
			(at 0 25.500076 270)
			(size 1.8034 0.508)
			(layers "B.Cu" "B.Mask" "B.Paste")
			(net "GND")
		)
		(pad "32" smd rect
			(at 0 26.34996 270)
			(size 1.8034 0.508)
			(layers "B.Cu" "B.Mask" "B.Paste")
			(net "M_G_DQ<22>")
		)
		(pad "33" smd rect
			(at 0 27.200098 270)
			(size 1.8034 0.508)
			(layers "B.Cu" "B.Mask" "B.Paste")
			(net "GND")
		)
		(pad "34" smd rect
			(at 0 28.049982 270)
			(size 1.8034 0.508)
			(layers "B.Cu" "B.Mask" "B.Paste")
			(net "M_G_DQ<18>")
		)
		(pad "35" smd rect
			(at 0 28.90012 270)
			(size 1.8034 0.508)
			(layers "B.Cu" "B.Mask" "B.Paste")
			(net "GND")
		)
		(pad "36" smd rect
			(at 0 29.750004 270)
			(size 1.8034 0.508)
			(layers "B.Cu" "B.Mask" "B.Paste")
			(net "M_G_DQ<28>")
		)
		(pad "37" smd rect
			(at 0 30.599888 270)
			(size 1.8034 0.508)
			(layers "B.Cu" "B.Mask" "B.Paste")
			(net "GND")
		)
		(pad "38" smd rect
			(at 0 31.450026 270)
			(size 1.8034 0.508)
			(layers "B.Cu" "B.Mask" "B.Paste")
			(net "M_G_DQ<24>")
		)
		(pad "39" smd rect
			(at 0 32.29991 270)
			(size 1.8034 0.508)
			(layers "B.Cu" "B.Mask" "B.Paste")
			(net "GND")
		)
		(pad "40" smd rect
			(at 0 33.150048 270)
			(size 1.8034 0.508)
			(layers "B.Cu" "B.Mask" "B.Paste")
			(net "M_G_DQS_DP<12>")
		)
		(pad "41" smd rect
			(at 0 33.999932 270)
			(size 1.8034 0.508)
			(layers "B.Cu" "B.Mask" "B.Paste")
			(net "M_G_DQS_DN<12>")
		)
		(pad "42" smd rect
			(at 0 34.85007 270)
			(size 1.8034 0.508)
			(layers "B.Cu" "B.Mask" "B.Paste")
			(net "GND")
		)
		(pad "43" smd rect
			(at 0 35.699954 270)
			(size 1.8034 0.508)
			(layers "B.Cu" "B.Mask" "B.Paste")
			(net "M_G_DQ<30>")
		)
		(pad "44" smd rect
			(at 0 36.550092 270)
			(size 1.8034 0.508)
			(layers "B.Cu" "B.Mask" "B.Paste")
			(net "GND")
		)
		(pad "45" smd rect
			(at 0 37.399976 270)
			(size 1.8034 0.508)
			(layers "B.Cu" "B.Mask" "B.Paste")
			(net "M_G_DQ<26>")
		)
		(pad "46" smd rect
			(at 0 38.250114 270)
			(size 1.8034 0.508)
			(layers "B.Cu" "B.Mask" "B.Paste")
			(net "GND")
		)
		(pad "47" smd rect
			(at 0 39.099998 270)
			(size 1.8034 0.508)
			(layers "B.Cu" "B.Mask" "B.Paste")
			(net "M_G_ECC<4>")
		)
		(pad "48" smd rect
			(at 0 39.949882 270)
			(size 1.8034 0.508)
			(layers "B.Cu" "B.Mask" "B.Paste")
			(net "GND")
		)
		(pad "49" smd rect
			(at 0 40.80002 270)
			(size 1.8034 0.508)
			(layers "B.Cu" "B.Mask" "B.Paste")
			(net "M_G_ECC<0>")
		)
		(pad "50" smd rect
			(at 0 41.649904 270)
			(size 1.8034 0.508)
			(layers "B.Cu" "B.Mask" "B.Paste")
			(net "GND")
		)
		(pad "51" smd rect
			(at 0 42.500042 270)
			(size 1.8034 0.508)
			(layers "B.Cu" "B.Mask" "B.Paste")
			(net "M_G_DQS_DP<17>")
		)
		(pad "52" smd rect
			(at 0 43.349926 270)
			(size 1.8034 0.508)
			(layers "B.Cu" "B.Mask" "B.Paste")
			(net "M_G_DQS_DN<17>")
		)
		(pad "53" smd rect
			(at 0 44.200064 270)
			(size 1.8034 0.508)
			(layers "B.Cu" "B.Mask" "B.Paste")
			(net "GND")
		)
		(pad "54" smd rect
			(at 0 45.049948 270)
			(size 1.8034 0.508)
			(layers "B.Cu" "B.Mask" "B.Paste")
			(net "M_G_ECC<6>")
		)
		(pad "55" smd rect
			(at 0 45.900086 270)
			(size 1.8034 0.508)
			(layers "B.Cu" "B.Mask" "B.Paste")
			(net "GND")
		)
		(pad "56" smd rect
			(at 0 46.74997 270)
			(size 1.8034 0.508)
			(layers "B.Cu" "B.Mask" "B.Paste")
			(net "M_G_ECC<2>")
		)
		(pad "57" smd rect
			(at 0 47.600108 270)
			(size 1.8034 0.508)
			(layers "B.Cu" "B.Mask" "B.Paste")
			(net "GND")
		)
		(pad "58" smd rect
			(at 0 48.449992 270)
			(size 1.8034 0.508)
			(layers "B.Cu" "B.Mask" "B.Paste")
			(net "M_GHJ_RST_N")
		)
		(pad "59" smd rect
			(at 0 49.299876 270)
			(size 1.8034 0.508)
			(layers "B.Cu" "B.Mask" "B.Paste")
			(net "PVDDQ_GHJ")
		)
		(pad "60" smd rect
			(at 0 50.150014 270)
			(size 1.8034 0.508)
			(layers "B.Cu" "B.Mask" "B.Paste")
			(net "M_G_CKE<2>")
		)
		(pad "61" smd rect
			(at 0 50.999898 270)
			(size 1.8034 0.508)
			(layers "B.Cu" "B.Mask" "B.Paste")
			(net "PVDDQ_GHJ")
		)
		(pad "62" smd rect
			(at 0 51.850036 270)
			(size 1.8034 0.508)
			(layers "B.Cu" "B.Mask" "B.Paste")
			(net "M_G_ACT_N")
		)
		(pad "63" smd rect
			(at 0 52.69992 270)
			(size 1.8034 0.508)
			(layers "B.Cu" "B.Mask" "B.Paste")
			(net "M_G_BG<0>")
		)
		(pad "64" smd rect
			(at 0 53.550058 270)
			(size 1.8034 0.508)
			(layers "B.Cu" "B.Mask" "B.Paste")
			(net "PVDDQ_GHJ")
		)
		(pad "65" smd rect
			(at 0 54.399942 270)
			(size 1.8034 0.508)
			(layers "B.Cu" "B.Mask" "B.Paste")
			(net "M_G_MA<12>")
		)
		(pad "66" smd rect
			(at 0 55.25008 270)
			(size 1.8034 0.508)
			(layers "B.Cu" "B.Mask" "B.Paste")
			(net "M_G_MA<9>")
		)
		(pad "67" smd rect
			(at 0 56.099964 270)
			(size 1.8034 0.508)
			(layers "B.Cu" "B.Mask" "B.Paste")
			(net "PVDDQ_GHJ")
		)
		(pad "68" smd rect
			(at 0 56.950102 270)
			(size 1.8034 0.508)
			(layers "B.Cu" "B.Mask" "B.Paste")
			(net "M_G_MA<8>")
		)
		(pad "69" smd rect
			(at 0 57.799986 270)
			(size 1.8034 0.508)
			(layers "B.Cu" "B.Mask" "B.Paste")
			(net "M_G_MA<6>")
		)
		(pad "70" smd rect
			(at 0 58.650124 270)
			(size 1.8034 0.508)
			(layers "B.Cu" "B.Mask" "B.Paste")
			(net "PVDDQ_GHJ")
		)
		(pad "71" smd rect
			(at 0 59.500008 270)
			(size 1.8034 0.508)
			(layers "B.Cu" "B.Mask" "B.Paste")
			(net "M_G_MA<3>")
		)
		(pad "72" smd rect
			(at 0 60.349892 270)
			(size 1.8034 0.508)
			(layers "B.Cu" "B.Mask" "B.Paste")
			(net "M_G_MA<1>")
		)
		(pad "73" smd rect
			(at 0 61.20003 270)
			(size 1.8034 0.508)
			(layers "B.Cu" "B.Mask" "B.Paste")
			(net "PVDDQ_GHJ")
		)
		(pad "74" smd rect
			(at 0 62.049914 270)
			(size 1.8034 0.508)
			(layers "B.Cu" "B.Mask" "B.Paste")
			(net "M_G_CLK_DP<2>")
		)
		(pad "75" smd rect
			(at 0 62.900052 270)
			(size 1.8034 0.508)
			(layers "B.Cu" "B.Mask" "B.Paste")
			(net "M_G_CLK_DN<2>")
		)
		(pad "76" smd rect
			(at 0 63.749936 270)
			(size 1.8034 0.508)
			(layers "B.Cu" "B.Mask" "B.Paste")
			(net "PVDDQ_GHJ")
		)
		(pad "77" smd rect
			(at 0 64.600074 270)
			(size 1.8034 0.508)
			(layers "B.Cu" "B.Mask" "B.Paste")
			(net "PVTT_GHJ")
		)
		(pad "78" smd rect
			(at 0 70.550024 270)
			(size 1.8034 0.508)
			(layers "B.Cu" "B.Mask" "B.Paste")
			(net "FM_DIMM_EVENT_COD_N")
		)
		(pad "79" smd rect
			(at 0 71.399908 270)
			(size 1.8034 0.508)
			(layers "B.Cu" "B.Mask" "B.Paste")
			(net "M_G_MA<0>")
		)
		(pad "80" smd rect
			(at 0 72.250046 270)
			(size 1.8034 0.508)
			(layers "B.Cu" "B.Mask" "B.Paste")
			(net "PVDDQ_GHJ")
		)
		(pad "81" smd rect
			(at 0 73.09993 270)
			(size 1.8034 0.508)
			(layers "B.Cu" "B.Mask" "B.Paste")
			(net "M_G_BA<0>")
		)
		(pad "82" smd rect
			(at 0 73.950068 270)
			(size 1.8034 0.508)
			(layers "B.Cu" "B.Mask" "B.Paste")
			(net "M_G_MA<16>")
		)
		(pad "83" smd rect
			(at 0 74.799952 270)
			(size 1.8034 0.508)
			(layers "B.Cu" "B.Mask" "B.Paste")
			(net "PVDDQ_GHJ")
		)
		(pad "84" smd rect
			(at 0 75.65009 270)
			(size 1.8034 0.508)
			(layers "B.Cu" "B.Mask" "B.Paste")
			(net "M_G_CS_N<4>")
		)
		(pad "85" smd rect
			(at 0 76.499974 270)
			(size 1.8034 0.508)
			(layers "B.Cu" "B.Mask" "B.Paste")
			(net "PVDDQ_GHJ")
		)
		(pad "86" smd rect
			(at 0 77.350112 270)
			(size 1.8034 0.508)
			(layers "B.Cu" "B.Mask" "B.Paste")
			(net "M_G_MA<15>")
		)
		(pad "87" smd rect
			(at 0 78.199996 270)
			(size 1.8034 0.508)
			(layers "B.Cu" "B.Mask" "B.Paste")
			(net "M_G_ODT<2>")
		)
		(pad "88" smd rect
			(at 0 79.04988 270)
			(size 1.8034 0.508)
			(layers "B.Cu" "B.Mask" "B.Paste")
			(net "PVDDQ_GHJ")
		)
		(pad "89" smd rect
			(at 0 79.900018 270)
			(size 1.8034 0.508)
			(layers "B.Cu" "B.Mask" "B.Paste")
			(net "M_G_CS_N<5>")
		)
		(pad "90" smd rect
			(at 0 80.749902 270)
			(size 1.8034 0.508)
			(layers "B.Cu" "B.Mask" "B.Paste")
			(net "PVDDQ_GHJ")
		)
		(pad "91" smd rect
			(at 0 81.60004 270)
			(size 1.8034 0.508)
			(layers "B.Cu" "B.Mask" "B.Paste")
			(net "M_G_ODT<3>")
		)
		(pad "92" smd rect
			(at 0 82.449924 270)
			(size 1.8034 0.508)
			(layers "B.Cu" "B.Mask" "B.Paste")
			(net "PVDDQ_GHJ")
		)
		(pad "93" smd rect
			(at 0 83.300062 270)
			(size 1.8034 0.508)
			(layers "B.Cu" "B.Mask" "B.Paste")
			(net "M_G_CS_N<6>")
		)
		(pad "94" smd rect
			(at 0 84.149946 270)
			(size 1.8034 0.508)
			(layers "B.Cu" "B.Mask" "B.Paste")
			(net "GND")
		)
		(pad "95" smd rect
			(at 0 85.000084 270)
			(size 1.8034 0.508)
			(layers "B.Cu" "B.Mask" "B.Paste")
			(net "M_G_DQ<36>")
		)
		(pad "96" smd rect
			(at 0 85.849968 270)
			(size 1.8034 0.508)
			(layers "B.Cu" "B.Mask" "B.Paste")
			(net "GND")
		)
		(pad "97" smd rect
			(at 0 86.700106 270)
			(size 1.8034 0.508)
			(layers "B.Cu" "B.Mask" "B.Paste")
			(net "M_G_DQ<32>")
		)
		(pad "98" smd rect
			(at 0 87.54999 270)
			(size 1.8034 0.508)
			(layers "B.Cu" "B.Mask" "B.Paste")
			(net "GND")
		)
		(pad "99" smd rect
			(at 0 88.399874 270)
			(size 1.8034 0.508)
			(layers "B.Cu" "B.Mask" "B.Paste")
			(net "M_G_DQS_DP<13>")
		)
		(pad "100" smd rect
			(at 0 89.250012 270)
			(size 1.8034 0.508)
			(layers "B.Cu" "B.Mask" "B.Paste")
			(net "M_G_DQS_DN<13>")
		)
		(pad "101" smd rect
			(at 0 90.099896 270)
			(size 1.8034 0.508)
			(layers "B.Cu" "B.Mask" "B.Paste")
			(net "GND")
		)
		(pad "102" smd rect
			(at 0 90.950034 270)
			(size 1.8034 0.508)
			(layers "B.Cu" "B.Mask" "B.Paste")
			(net "M_G_DQ<38>")
		)
		(pad "103" smd rect
			(at 0 91.799918 270)
			(size 1.8034 0.508)
			(layers "B.Cu" "B.Mask" "B.Paste")
			(net "GND")
		)
		(pad "104" smd rect
			(at 0 92.650056 270)
			(size 1.8034 0.508)
			(layers "B.Cu" "B.Mask" "B.Paste")
			(net "M_G_DQ<34>")
		)
		(pad "105" smd rect
			(at 0 93.49994 270)
			(size 1.8034 0.508)
			(layers "B.Cu" "B.Mask" "B.Paste")
			(net "GND")
		)
		(pad "106" smd rect
			(at 0 94.350078 270)
			(size 1.8034 0.508)
			(layers "B.Cu" "B.Mask" "B.Paste")
			(net "M_G_DQ<44>")
		)
		(pad "107" smd rect
			(at 0 95.199962 270)
			(size 1.8034 0.508)
			(layers "B.Cu" "B.Mask" "B.Paste")
			(net "GND")
		)
		(pad "108" smd rect
			(at 0 96.0501 270)
			(size 1.8034 0.508)
			(layers "B.Cu" "B.Mask" "B.Paste")
			(net "M_G_DQ<40>")
		)
		(pad "109" smd rect
			(at 0 96.899984 270)
			(size 1.8034 0.508)
			(layers "B.Cu" "B.Mask" "B.Paste")
			(net "GND")
		)
		(pad "110" smd rect
			(at 0 97.750122 270)
			(size 1.8034 0.508)
			(layers "B.Cu" "B.Mask" "B.Paste")
			(net "M_G_DQS_DP<14>")
		)
		(pad "111" smd rect
			(at 0 98.600006 270)
			(size 1.8034 0.508)
			(layers "B.Cu" "B.Mask" "B.Paste")
			(net "M_G_DQS_DN<14>")
		)
		(pad "112" smd rect
			(at 0 99.44989 270)
			(size 1.8034 0.508)
			(layers "B.Cu" "B.Mask" "B.Paste")
			(net "GND")
		)
		(pad "113" smd rect
			(at 0 100.300028 270)
			(size 1.8034 0.508)
			(layers "B.Cu" "B.Mask" "B.Paste")
			(net "M_G_DQ<46>")
		)
		(pad "114" smd rect
			(at 0 101.149912 270)
			(size 1.8034 0.508)
			(layers "B.Cu" "B.Mask" "B.Paste")
			(net "GND")
		)
		(pad "115" smd rect
			(at 0 102.00005 270)
			(size 1.8034 0.508)
			(layers "B.Cu" "B.Mask" "B.Paste")
			(net "M_G_DQ<42>")
		)
		(pad "116" smd rect
			(at 0 102.849934 270)
			(size 1.8034 0.508)
			(layers "B.Cu" "B.Mask" "B.Paste")
			(net "GND")
		)
		(pad "117" smd rect
			(at 0 103.700072 270)
			(size 1.8034 0.508)
			(layers "B.Cu" "B.Mask" "B.Paste")
			(net "M_G_DQ<52>")
		)
		(pad "118" smd rect
			(at 0 104.549956 270)
			(size 1.8034 0.508)
			(layers "B.Cu" "B.Mask" "B.Paste")
			(net "GND")
		)
		(pad "119" smd rect
			(at 0 105.400094 270)
			(size 1.8034 0.508)
			(layers "B.Cu" "B.Mask" "B.Paste")
			(net "M_G_DQ<48>")
		)
		(pad "120" smd rect
			(at 0 106.249978 270)
			(size 1.8034 0.508)
			(layers "B.Cu" "B.Mask" "B.Paste")
			(net "GND")
		)
	)
)
